(kicad_pcb
	(version 20260206)
	(generator "pcbnew")
	(generator_version "10.0")
	(general
		(thickness 1.6)
		(legacy_teardrops no)
	)
	(paper "A4")
	(title_block
		(title "04192023_DAF0TMB3IC0_F0TG_MB_C_brd_V02_OCP.brd")
		(comment 1 "Grand Teton / footprints 6199-6204 of 8354")
	)
	(layers
		(0 "F.Cu" signal "TOP")
		(4 "In1.Cu" signal "GND")
		(6 "In2.Cu" signal "IN1")
		(8 "In3.Cu" signal "GND1")
		(10 "In4.Cu" signal "IN2")
		(12 "In5.Cu" signal "GND2")
		(14 "In6.Cu" signal "IN3")
		(16 "In7.Cu" signal "GND3")
		(18 "In8.Cu" signal "VCC")
		(20 "In9.Cu" signal "VCC1")
		(22 "In10.Cu" signal "GND4")
		(24 "In11.Cu" signal "IN4")
		(26 "In12.Cu" signal "GND5")
		(28 "In13.Cu" signal "IN5")
		(30 "In14.Cu" signal "GND6")
		(32 "In15.Cu" signal "IN6")
		(34 "In16.Cu" signal "GND7")
		(2 "B.Cu" signal "BOTTOM")
		(9 "F.Adhes" user "F.Adhesive")
		(11 "B.Adhes" user "B.Adhesive")
		(13 "F.Paste" user "Package Geometry/Pastemask Top")
		(15 "B.Paste" user "Package Geometry/Pastemask Bottom")
		(5 "F.SilkS" user "Ref Des/Silkscreen Top")
		(7 "B.SilkS" user "Ref Des/Silkscreen Bottom")
		(1 "F.Mask" user "Board Geometry/Soldermask Top")
		(3 "B.Mask" user "Board Geometry/Soldermask Bottom")
		(17 "Dwgs.User" user "User.Drawings")
		(19 "Cmts.User" user "User.Comments")
		(21 "Eco1.User" user "User.Eco1")
		(23 "Eco2.User" user "User.Eco2")
		(25 "Edge.Cuts" user "Board Geometry/Outline")
		(27 "Margin" user)
		(31 "F.CrtYd" user "Package Geometry/Place Bound Top")
		(29 "B.CrtYd" user "Package Geometry/Place Bound Bottom")
		(35 "F.Fab" user "Ref Des/Assembly Top")
		(33 "B.Fab" user "Ref Des/Assembly Bottom")
	)
	(footprint ""
		(layer "B.Cu")
		(at 122.18289 -245.488206)
		(property "Reference" "C2318"
			(at 0 0 0)
			(layer "B.SilkS")
			(hide yes)
			(effects
				(font
					(size 1.27 1.27)
				)
				(justify mirror)
			)
		)
		(property "Value" ""
			(at 0 0 0)
			(layer "B.Fab")
			(effects
				(font
					(size 1.27 1.27)
				)
				(justify mirror)
			)
		)
		(duplicate_pad_numbers_are_jumpers no)
		(fp_line
			(start -0.7874 -0.4064)
			(end -0.7874 0.4064)
			(stroke
				(width 0.1524)
				(type default)
			)
			(layer "B.SilkS")
		)
		(fp_line
			(start -0.7874 0.4064)
			(end 0.7874 0.4064)
			(stroke
				(width 0.1524)
				(type default)
			)
			(layer "B.SilkS")
		)
		(fp_line
			(start 0.7874 -0.4064)
			(end -0.7874 -0.4064)
			(stroke
				(width 0.1524)
				(type default)
			)
			(layer "B.SilkS")
		)
		(fp_line
			(start 0.7874 0.4064)
			(end 0.7874 -0.4064)
			(stroke
				(width 0.1524)
				(type default)
			)
			(layer "B.SilkS")
		)
		(fp_line
			(start -0.67945 -0.3048)
			(end -0.67945 0.3048)
			(stroke
				(width 0.1)
				(type default)
			)
			(layer "B.Fab")
		)
		(fp_line
			(start -0.67945 0.3048)
			(end -0.120396 0.3048)
			(stroke
				(width 0.1)
				(type default)
			)
			(layer "B.Fab")
		)
		(fp_line
			(start -0.12065 -0.3048)
			(end -0.67945 -0.3048)
			(stroke
				(width 0.1)
				(type default)
			)
			(layer "B.Fab")
		)
		(fp_line
			(start -0.12065 -0.2794)
			(end -0.12065 -0.3048)
			(stroke
				(width 0.1)
				(type default)
			)
			(layer "B.Fab")
		)
		(fp_line
			(start -0.120396 0.2794)
			(end 0.12065 0.2794)
			(stroke
				(width 0.1)
				(type default)
			)
			(layer "B.Fab")
		)
		(fp_line
			(start -0.120396 0.3048)
			(end -0.120396 0.2794)
			(stroke
				(width 0.1)
				(type default)
			)
			(layer "B.Fab")
		)
		(fp_line
			(start 0.12065 -0.305054)
			(end 0.12065 -0.2794)
			(stroke
				(width 0.1)
				(type default)
			)
			(layer "B.Fab")
		)
		(fp_line
			(start 0.12065 -0.2794)
			(end -0.12065 -0.2794)
			(stroke
				(width 0.1)
				(type default)
			)
			(layer "B.Fab")
		)
		(fp_line
			(start 0.12065 0.2794)
			(end 0.12065 0.3048)
			(stroke
				(width 0.1)
				(type default)
			)
			(layer "B.Fab")
		)
		(fp_line
			(start 0.12065 0.3048)
			(end 0.67945 0.3048)
			(stroke
				(width 0.1)
				(type default)
			)
			(layer "B.Fab")
		)
		(fp_line
			(start 0.67945 -0.305054)
			(end 0.12065 -0.305054)
			(stroke
				(width 0.1)
				(type default)
			)
			(layer "B.Fab")
		)
		(fp_line
			(start 0.67945 0.3048)
			(end 0.67945 -0.305054)
			(stroke
				(width 0.1)
				(type default)
			)
			(layer "B.Fab")
		)
		(pad "1" smd circle
			(at 0.40005 0 180)
			(size 0 0)
			(layers "B.Cu" "B.Mask" "B.Paste")
			(net "PVDDCR_CPU0_P1")
		)
		(pad "2" smd circle
			(at -0.40005 0 180)
			(size 0 0)
			(layers "B.Cu" "B.Mask" "B.Paste")
			(net "GND")
		)
	)
	(footprint ""
		(layer "B.Cu")
		(at 372.818406 -189.50432 90)
		(property "Reference" "PC498"
			(at 6.582664 -0.550926 270)
			(unlocked yes)
			(layer "B.SilkS")
			(effects
				(font
					(size 0.7874 0.5842)
					(thickness 0.1524)
				)
				(justify left mirror)
			)
		)
		(property "Value" ""
			(at 0 0 90)
			(layer "B.Fab")
			(effects
				(font
					(size 1.27 1.27)
				)
				(justify mirror)
			)
		)
		(duplicate_pad_numbers_are_jumpers no)
		(fp_line
			(start 4.533392 -2.249932)
			(end -4.533392 -2.249932)
			(stroke
				(width 0.1524)
				(type default)
			)
			(layer "B.SilkS")
		)
		(fp_line
			(start -4.533392 -2.249932)
			(end -4.533392 2.249932)
			(stroke
				(width 0.1524)
				(type default)
			)
			(layer "B.SilkS")
		)
		(fp_line
			(start 4.533392 2.249932)
			(end 4.533392 -2.249932)
			(stroke
				(width 0.1524)
				(type default)
			)
			(layer "B.SilkS")
		)
		(fp_line
			(start -4.533392 2.249932)
			(end 4.533392 2.249932)
			(stroke
				(width 0.1524)
				(type default)
			)
			(layer "B.SilkS")
		)
		(fp_rect
			(start 4.533392 -2.326132)
			(end 5.39242 2.326132)
			(stroke
				(width 0)
				(type default)
			)
			(fill yes)
			(layer "B.SilkS")
		)
		(fp_line
			(start 3.750056 -2.249932)
			(end -3.750056 -2.249932)
			(stroke
				(width 0.1)
				(type default)
			)
			(layer "B.Fab")
		)
		(fp_line
			(start -3.750056 -2.249932)
			(end -3.750056 2.249932)
			(stroke
				(width 0.1)
				(type default)
			)
			(layer "B.Fab")
		)
		(fp_line
			(start 3.750056 2.249932)
			(end 3.750056 -2.249932)
			(stroke
				(width 0.1)
				(type default)
			)
			(layer "B.Fab")
		)
		(fp_line
			(start -3.750056 2.249932)
			(end 3.750056 2.249932)
			(stroke
				(width 0.1)
				(type default)
			)
			(layer "B.Fab")
		)
		(fp_text user "-"
			(at -4.8514 -0.14605 90)
			(unlocked yes)
			(layer "B.SilkS")
			(effects
				(font
					(size 1.905 1.4224)
					(thickness 0.1524)
				)
				(justify left mirror)
			)
		)
		(fp_text user "+"
			(at 6.322314 0.786384 0)
			(unlocked yes)
			(layer "B.SilkS")
			(effects
				(font
					(size 1.905 1.4224)
					(thickness 0.1524)
				)
				(justify left mirror)
			)
		)
		(fp_text user "-"
			(at -4.8514 -0.14605 90)
			(unlocked yes)
			(layer "B.Fab")
			(effects
				(font
					(size 1.905 1.4224)
					(thickness 0.1524)
				)
				(justify left mirror)
			)
		)
		(fp_text user "+"
			(at 6.322314 0.786384 0)
			(unlocked yes)
			(layer "B.Fab")
			(effects
				(font
					(size 1.905 1.4224)
					(thickness 0.1524)
				)
				(justify left mirror)
			)
		)
		(pad "1" smd rect
			(at 3.199892 0 270)
			(size 2.413 2.8194)
			(layers "B.Cu" "B.Mask" "B.Paste")
			(net "PVDDCR_CPU0_P0")
		)
		(pad "2" smd rect
			(at -3.199892 0 270)
			(size 2.413 2.8194)
			(layers "B.Cu" "B.Mask" "B.Paste")
			(net "GND")
		)
	)
	(footprint ""
		(layer "B.Cu")
		(at 372.937278 -147.568158 180)
		(property "Reference" "PR305"
			(at 0 0 0)
			(layer "B.SilkS")
			(hide yes)
			(effects
				(font
					(size 1.27 1.27)
				)
				(justify mirror)
			)
		)
		(property "Value" ""
			(at 0 0 0)
			(layer "B.Fab")
			(effects
				(font
					(size 1.27 1.27)
				)
				(justify mirror)
			)
		)
		(duplicate_pad_numbers_are_jumpers no)
		(fp_line
			(start 0.7874 0.4064)
			(end 0.7874 -0.4064)
			(stroke
				(width 0.1524)
				(type default)
			)
			(layer "B.SilkS")
		)
		(fp_line
			(start 0.7874 -0.4064)
			(end -0.7874 -0.4064)
			(stroke
				(width 0.1524)
				(type default)
			)
			(layer "B.SilkS")
		)
		(fp_line
			(start -0.7874 0.4064)
			(end 0.7874 0.4064)
			(stroke
				(width 0.1524)
				(type default)
			)
			(layer "B.SilkS")
		)
		(fp_line
			(start -0.7874 -0.4064)
			(end -0.7874 0.4064)
			(stroke
				(width 0.1524)
				(type default)
			)
			(layer "B.SilkS")
		)
		(fp_line
			(start 0.67945 0.3048)
			(end 0.67945 -0.305054)
			(stroke
				(width 0.1)
				(type default)
			)
			(layer "B.Fab")
		)
		(fp_line
			(start 0.67945 -0.305054)
			(end 0.12065 -0.305054)
			(stroke
				(width 0.1)
				(type default)
			)
			(layer "B.Fab")
		)
		(fp_line
			(start 0.12065 0.3048)
			(end 0.67945 0.3048)
			(stroke
				(width 0.1)
				(type default)
			)
			(layer "B.Fab")
		)
		(fp_line
			(start 0.12065 0.2794)
			(end 0.12065 0.3048)
			(stroke
				(width 0.1)
				(type default)
			)
			(layer "B.Fab")
		)
		(fp_line
			(start 0.12065 -0.2794)
			(end -0.12065 -0.2794)
			(stroke
				(width 0.1)
				(type default)
			)
			(layer "B.Fab")
		)
		(fp_line
			(start 0.12065 -0.305054)
			(end 0.12065 -0.2794)
			(stroke
				(width 0.1)
				(type default)
			)
			(layer "B.Fab")
		)
		(fp_line
			(start -0.120396 0.3048)
			(end -0.120396 0.2794)
			(stroke
				(width 0.1)
				(type default)
			)
			(layer "B.Fab")
		)
		(fp_line
			(start -0.120396 0.2794)
			(end 0.12065 0.2794)
			(stroke
				(width 0.1)
				(type default)
			)
			(layer "B.Fab")
		)
		(fp_line
			(start -0.12065 -0.2794)
			(end -0.12065 -0.3048)
			(stroke
				(width 0.1)
				(type default)
			)
			(layer "B.Fab")
		)
		(fp_line
			(start -0.12065 -0.3048)
			(end -0.67945 -0.3048)
			(stroke
				(width 0.1)
				(type default)
			)
			(layer "B.Fab")
		)
		(fp_line
			(start -0.67945 0.3048)
			(end -0.120396 0.3048)
			(stroke
				(width 0.1)
				(type default)
			)
			(layer "B.Fab")
		)
		(fp_line
			(start -0.67945 -0.3048)
			(end -0.67945 0.3048)
			(stroke
				(width 0.1)
				(type default)
			)
			(layer "B.Fab")
		)
		(pad "1" smd circle
			(at 0.40005 0)
			(size 0 0)
			(layers "B.Cu" "B.Mask" "B.Paste")
			(net "SVID_PVDDCR_CPU0_P0_SVTI")
		)
		(pad "2" smd circle
			(at -0.40005 0)
			(size 0 0)
			(layers "B.Cu" "B.Mask" "B.Paste")
			(net "SVID_PVDDCR_CPU0_P0_SVTI_R")
		)
	)
	(footprint ""
		(layer "B.Cu")
		(at 369.62588 -259.729986)
		(property "Reference" "C2577"
			(at 0 0 0)
			(layer "B.SilkS")
			(hide yes)
			(effects
				(font
					(size 1.27 1.27)
				)
				(justify mirror)
			)
		)
		(property "Value" ""
			(at 0 0 0)
			(layer "B.Fab")
			(effects
				(font
					(size 1.27 1.27)
				)
				(justify mirror)
			)
		)
		(duplicate_pad_numbers_are_jumpers no)
		(fp_line
			(start -0.7874 -0.4064)
			(end -0.7874 0.4064)
			(stroke
				(width 0.1524)
				(type default)
			)
			(layer "B.SilkS")
		)
		(fp_line
			(start -0.7874 0.4064)
			(end 0.7874 0.4064)
			(stroke
				(width 0.1524)
				(type default)
			)
			(layer "B.SilkS")
		)
		(fp_line
			(start 0.7874 -0.4064)
			(end -0.7874 -0.4064)
			(stroke
				(width 0.1524)
				(type default)
			)
			(layer "B.SilkS")
		)
		(fp_line
			(start 0.7874 0.4064)
			(end 0.7874 -0.4064)
			(stroke
				(width 0.1524)
				(type default)
			)
			(layer "B.SilkS")
		)
		(fp_line
			(start -0.67945 -0.3048)
			(end -0.67945 0.3048)
			(stroke
				(width 0.1)
				(type default)
			)
			(layer "B.Fab")
		)
		(fp_line
			(start -0.67945 0.3048)
			(end -0.120396 0.3048)
			(stroke
				(width 0.1)
				(type default)
			)
			(layer "B.Fab")
		)
		(fp_line
			(start -0.12065 -0.3048)
			(end -0.67945 -0.3048)
			(stroke
				(width 0.1)
				(type default)
			)
			(layer "B.Fab")
		)
		(fp_line
			(start -0.12065 -0.2794)
			(end -0.12065 -0.3048)
			(stroke
				(width 0.1)
				(type default)
			)
			(layer "B.Fab")
		)
		(fp_line
			(start -0.120396 0.2794)
			(end 0.12065 0.2794)
			(stroke
				(width 0.1)
				(type default)
			)
			(layer "B.Fab")
		)
		(fp_line
			(start -0.120396 0.3048)
			(end -0.120396 0.2794)
			(stroke
				(width 0.1)
				(type default)
			)
			(layer "B.Fab")
		)
		(fp_line
			(start 0.12065 -0.305054)
			(end 0.12065 -0.2794)
			(stroke
				(width 0.1)
				(type default)
			)
			(layer "B.Fab")
		)
		(fp_line
			(start 0.12065 -0.2794)
			(end -0.12065 -0.2794)
			(stroke
				(width 0.1)
				(type default)
			)
			(layer "B.Fab")
		)
		(fp_line
			(start 0.12065 0.2794)
			(end 0.12065 0.3048)
			(stroke
				(width 0.1)
				(type default)
			)
			(layer "B.Fab")
		)
		(fp_line
			(start 0.12065 0.3048)
			(end 0.67945 0.3048)
			(stroke
				(width 0.1)
				(type default)
			)
			(layer "B.Fab")
		)
		(fp_line
			(start 0.67945 -0.305054)
			(end 0.12065 -0.305054)
			(stroke
				(width 0.1)
				(type default)
			)
			(layer "B.Fab")
		)
		(fp_line
			(start 0.67945 0.3048)
			(end 0.67945 -0.305054)
			(stroke
				(width 0.1)
				(type default)
			)
			(layer "B.Fab")
		)
		(pad "1" smd circle
			(at 0.40005 0 180)
			(size 0 0)
			(layers "B.Cu" "B.Mask" "B.Paste")
			(net "PVDDCR_SOC_P0")
		)
		(pad "2" smd circle
			(at -0.40005 0 180)
			(size 0 0)
			(layers "B.Cu" "B.Mask" "B.Paste")
			(net "GND")
		)
	)
	(footprint ""
		(layer "B.Cu")
		(at 208.461356 -380.206504)
		(property "Reference" "PR2512"
			(at 0 0 0)
			(layer "B.SilkS")
			(hide yes)
			(effects
				(font
					(size 1.27 1.27)
				)
				(justify mirror)
			)
		)
		(property "Value" ""
			(at 0 0 0)
			(layer "B.Fab")
			(effects
				(font
					(size 1.27 1.27)
				)
				(justify mirror)
			)
		)
		(duplicate_pad_numbers_are_jumpers no)
		(fp_line
			(start -0.7874 -0.4064)
			(end -0.7874 0.4064)
			(stroke
				(width 0.1524)
				(type default)
			)
			(layer "B.SilkS")
		)
		(fp_line
			(start -0.7874 0.4064)
			(end 0.7874 0.4064)
			(stroke
				(width 0.1524)
				(type default)
			)
			(layer "B.SilkS")
		)
		(fp_line
			(start 0.7874 -0.4064)
			(end -0.7874 -0.4064)
			(stroke
				(width 0.1524)
				(type default)
			)
			(layer "B.SilkS")
		)
		(fp_line
			(start 0.7874 0.4064)
			(end 0.7874 -0.4064)
			(stroke
				(width 0.1524)
				(type default)
			)
			(layer "B.SilkS")
		)
		(fp_line
			(start -0.67945 -0.3048)
			(end -0.67945 0.3048)
			(stroke
				(width 0.1)
				(type default)
			)
			(layer "B.Fab")
		)
		(fp_line
			(start -0.67945 0.3048)
			(end -0.120396 0.3048)
			(stroke
				(width 0.1)
				(type default)
			)
			(layer "B.Fab")
		)
		(fp_line
			(start -0.12065 -0.3048)
			(end -0.67945 -0.3048)
			(stroke
				(width 0.1)
				(type default)
			)
			(layer "B.Fab")
		)
		(fp_line
			(start -0.12065 -0.2794)
			(end -0.12065 -0.3048)
			(stroke
				(width 0.1)
				(type default)
			)
			(layer "B.Fab")
		)
		(fp_line
			(start -0.120396 0.2794)
			(end 0.12065 0.2794)
			(stroke
				(width 0.1)
				(type default)
			)
			(layer "B.Fab")
		)
		(fp_line
			(start -0.120396 0.3048)
			(end -0.120396 0.2794)
			(stroke
				(width 0.1)
				(type default)
			)
			(layer "B.Fab")
		)
		(fp_line
			(start 0.12065 -0.305054)
			(end 0.12065 -0.2794)
			(stroke
				(width 0.1)
				(type default)
			)
			(layer "B.Fab")
		)
		(fp_line
			(start 0.12065 -0.2794)
			(end -0.12065 -0.2794)
			(stroke
				(width 0.1)
				(type default)
			)
			(layer "B.Fab")
		)
		(fp_line
			(start 0.12065 0.2794)
			(end 0.12065 0.3048)
			(stroke
				(width 0.1)
				(type default)
			)
			(layer "B.Fab")
		)
		(fp_line
			(start 0.12065 0.3048)
			(end 0.67945 0.3048)
			(stroke
				(width 0.1)
				(type default)
			)
			(layer "B.Fab")
		)
		(fp_line
			(start 0.67945 -0.305054)
			(end 0.12065 -0.305054)
			(stroke
				(width 0.1)
				(type default)
			)
			(layer "B.Fab")
		)
		(fp_line
			(start 0.67945 0.3048)
			(end 0.67945 -0.305054)
			(stroke
				(width 0.1)
				(type default)
			)
			(layer "B.Fab")
		)
		(pad "1" smd circle
			(at 0.40005 0 180)
			(size 0 0)
			(layers "B.Cu" "B.Mask" "B.Paste")
			(net "P12V_HSC_ADC_P")
		)
		(pad "2" smd circle
			(at -0.40005 0 180)
			(size 0 0)
			(layers "B.Cu" "B.Mask" "B.Paste")
			(net "P12V_HSC_SENSE2_R3_P")
		)
	)
	(footprint ""
		(layer "B.Cu")
		(at 386.091176 -398.942052 90)
		(property "Reference" "C1026"
			(at 0 0 90)
			(layer "B.SilkS")
			(hide yes)
			(effects
				(font
					(size 1.27 1.27)
				)
				(justify mirror)
			)
		)
		(property "Value" ""
			(at 0 0 90)
			(layer "B.Fab")
			(effects
				(font
					(size 1.27 1.27)
				)
				(justify mirror)
			)
		)
		(duplicate_pad_numbers_are_jumpers no)
		(fp_line
			(start 0.7874 -0.4064)
			(end -0.7874 -0.4064)
			(stroke
				(width 0.1524)
				(type default)
			)
			(layer "B.SilkS")
		)
		(fp_line
			(start -0.7874 -0.4064)
			(end -0.7874 0.4064)
			(stroke
				(width 0.1524)
				(type default)
			)
			(layer "B.SilkS")
		)
		(fp_line
			(start 0.7874 0.4064)
			(end 0.7874 -0.4064)
			(stroke
				(width 0.1524)
				(type default)
			)
			(layer "B.SilkS")
		)
		(fp_line
			(start -0.7874 0.4064)
			(end 0.7874 0.4064)
			(stroke
				(width 0.1524)
				(type default)
			)
			(layer "B.SilkS")
		)
		(fp_line
			(start 0.67945 -0.305054)
			(end 0.12065 -0.305054)
			(stroke
				(width 0.1)
				(type default)
			)
			(layer "B.Fab")
		)
		(fp_line
			(start 0.12065 -0.305054)
			(end 0.12065 -0.2794)
			(stroke
				(width 0.1)
				(type default)
			)
			(layer "B.Fab")
		)
		(fp_line
			(start -0.12065 -0.3048)
			(end -0.67945 -0.3048)
			(stroke
				(width 0.1)
				(type default)
			)
			(layer "B.Fab")
		)
		(fp_line
			(start -0.67945 -0.3048)
			(end -0.67945 0.3048)
			(stroke
				(width 0.1)
				(type default)
			)
			(layer "B.Fab")
		)
		(fp_line
			(start 0.12065 -0.2794)
			(end -0.12065 -0.2794)
			(stroke
				(width 0.1)
				(type default)
			)
			(layer "B.Fab")
		)
		(fp_line
			(start -0.12065 -0.2794)
			(end -0.12065 -0.3048)
			(stroke
				(width 0.1)
				(type default)
			)
			(layer "B.Fab")
		)
		(fp_line
			(start 0.12065 0.2794)
			(end 0.12065 0.3048)
			(stroke
				(width 0.1)
				(type default)
			)
			(layer "B.Fab")
		)
		(fp_line
			(start -0.120396 0.2794)
			(end 0.12065 0.2794)
			(stroke
				(width 0.1)
				(type default)
			)
			(layer "B.Fab")
		)
		(fp_line
			(start 0.67945 0.3048)
			(end 0.67945 -0.305054)
			(stroke
				(width 0.1)
				(type default)
			)
			(layer "B.Fab")
		)
		(fp_line
			(start 0.12065 0.3048)
			(end 0.67945 0.3048)
			(stroke
				(width 0.1)
				(type default)
			)
			(layer "B.Fab")
		)
		(fp_line
			(start -0.120396 0.3048)
			(end -0.120396 0.2794)
			(stroke
				(width 0.1)
				(type default)
			)
			(layer "B.Fab")
		)
		(fp_line
			(start -0.67945 0.3048)
			(end -0.120396 0.3048)
			(stroke
				(width 0.1)
				(type default)
			)
			(layer "B.Fab")
		)
		(pad "1" smd circle
			(at 0.40005 0 270)
			(size 0 0)
			(layers "B.Cu" "B.Mask" "B.Paste")
			(net "P0V9_CPU0_RT3_2A")
		)
		(pad "2" smd circle
			(at -0.40005 0 270)
			(size 0 0)
			(layers "B.Cu" "B.Mask" "B.Paste")
			(net "GND")
		)
	)
)
